# T6G (Grand Teton) — schematic netlist excerpt (pin names and nets, part order shuffled) for the footprints in the layout excerpt that follows; sources: Cadence DE-HDL packaged netlist, KiCad conversion of 04192023_DAF0TMB3IC0_F0TG_MB_C_brd_V02_OCP.brd

C74  Q_CAP  0.1UF 25V 10% EMPTY  pkg 0402  page 240 : A = RST_SMB_SWITCH_R_N ; B = GND
R516  Q_RES  2.2K 5% CHIP  pkg 0402LF  page 54 : A = P3V3_AUX ; B = CPU1_CORETYPE0
C137  Q_CAP  0.1UF 10V 10% X7S  pkg C0201  page 323 : A = P0V9_CPU1_RT_2D ; B = GND

(kicad_pcb
	(version 20260206)
	(generator "pcbnew")
	(generator_version "10.0")
	(general
		(thickness 1.6)
		(legacy_teardrops no)
	)
	(paper "A4")
	(title_block
		(title "04192023_DAF0TMB3IC0_F0TG_MB_C_brd_V02_OCP.brd")
		(comment 1 "Grand Teton / footprints 7860-7862 of 8354")
	)
	(layers
		(0 "F.Cu" signal "TOP")
		(4 "In1.Cu" signal "GND")
		(6 "In2.Cu" signal "IN1")
		(8 "In3.Cu" signal "GND1")
		(10 "In4.Cu" signal "IN2")
		(12 "In5.Cu" signal "GND2")
		(14 "In6.Cu" signal "IN3")
		(16 "In7.Cu" signal "GND3")
		(18 "In8.Cu" signal "VCC")
		(20 "In9.Cu" signal "VCC1")
		(22 "In10.Cu" signal "GND4")
		(24 "In11.Cu" signal "IN4")
		(26 "In12.Cu" signal "GND5")
		(28 "In13.Cu" signal "IN5")
		(30 "In14.Cu" signal "GND6")
		(32 "In15.Cu" signal "IN6")
		(34 "In16.Cu" signal "GND7")
		(2 "B.Cu" signal "BOTTOM")
		(9 "F.Adhes" user "F.Adhesive")
		(11 "B.Adhes" user "B.Adhesive")
		(13 "F.Paste" user "Package Geometry/Pastemask Top")
		(15 "B.Paste" user "Package Geometry/Pastemask Bottom")
		(5 "F.SilkS" user "Ref Des/Silkscreen Top")
		(7 "B.SilkS" user "Ref Des/Silkscreen Bottom")
		(1 "F.Mask" user "Board Geometry/Soldermask Top")
		(3 "B.Mask" user "Board Geometry/Soldermask Bottom")
		(17 "Dwgs.User" user "User.Drawings")
		(19 "Cmts.User" user "User.Comments")
		(21 "Eco1.User" user "User.Eco1")
		(23 "Eco2.User" user "User.Eco2")
		(25 "Edge.Cuts" user "Board Geometry/Outline")
		(27 "Margin" user)
		(31 "F.CrtYd" user "Package Geometry/Place Bound Top")
		(29 "B.CrtYd" user "Package Geometry/Place Bound Bottom")
		(35 "F.Fab" user "Ref Des/Assembly Top")
		(33 "B.Fab" user "Ref Des/Assembly Bottom")
	)
	(footprint ""
		(layer "B.Cu")
		(at 63.619634 -197.202552 180)
		(property "Reference" "R516"
			(at 0 0 0)
			(layer "B.SilkS")
			(hide yes)
			(effects
				(font
					(size 1.27 1.27)
				)
				(justify mirror)
			)
		)
		(property "Value" ""
			(at 0 0 0)
			(layer "B.Fab")
			(effects
				(font
					(size 1.27 1.27)
				)
				(justify mirror)
			)
		)
		(duplicate_pad_numbers_are_jumpers no)
		(fp_line
			(start 0.7874 0.4064)
			(end 0.7874 -0.4064)
			(stroke
				(width 0.1524)
				(type default)
			)
			(layer "B.SilkS")
		)
		(fp_line
			(start 0.7874 -0.4064)
			(end -0.7874 -0.4064)
			(stroke
				(width 0.1524)
				(type default)
			)
			(layer "B.SilkS")
		)
		(fp_line
			(start -0.7874 0.4064)
			(end 0.7874 0.4064)
			(stroke
				(width 0.1524)
				(type default)
			)
			(layer "B.SilkS")
		)
		(fp_line
			(start -0.7874 -0.4064)
			(end -0.7874 0.4064)
			(stroke
				(width 0.1524)
				(type default)
			)
			(layer "B.SilkS")
		)
		(fp_line
			(start 0.67945 0.3048)
			(end 0.67945 -0.305054)
			(stroke
				(width 0.1)
				(type default)
			)
			(layer "B.Fab")
		)
		(fp_line
			(start 0.67945 -0.305054)
			(end 0.12065 -0.305054)
			(stroke
				(width 0.1)
				(type default)
			)
			(layer "B.Fab")
		)
		(fp_line
			(start 0.12065 0.3048)
			(end 0.67945 0.3048)
			(stroke
				(width 0.1)
				(type default)
			)
			(layer "B.Fab")
		)
		(fp_line
			(start 0.12065 0.2794)
			(end 0.12065 0.3048)
			(stroke
				(width 0.1)
				(type default)
			)
			(layer "B.Fab")
		)
		(fp_line
			(start 0.12065 -0.2794)
			(end -0.12065 -0.2794)
			(stroke
				(width 0.1)
				(type default)
			)
			(layer "B.Fab")
		)
		(fp_line
			(start 0.12065 -0.305054)
			(end 0.12065 -0.2794)
			(stroke
				(width 0.1)
				(type default)
			)
			(layer "B.Fab")
		)
		(fp_line
			(start -0.120396 0.3048)
			(end -0.120396 0.2794)
			(stroke
				(width 0.1)
				(type default)
			)
			(layer "B.Fab")
		)
		(fp_line
			(start -0.120396 0.2794)
			(end 0.12065 0.2794)
			(stroke
				(width 0.1)
				(type default)
			)
			(layer "B.Fab")
		)
		(fp_line
			(start -0.12065 -0.2794)
			(end -0.12065 -0.3048)
			(stroke
				(width 0.1)
				(type default)
			)
			(layer "B.Fab")
		)
		(fp_line
			(start -0.12065 -0.3048)
			(end -0.67945 -0.3048)
			(stroke
				(width 0.1)
				(type default)
			)
			(layer "B.Fab")
		)
		(fp_line
			(start -0.67945 0.3048)
			(end -0.120396 0.3048)
			(stroke
				(width 0.1)
				(type default)
			)
			(layer "B.Fab")
		)
		(fp_line
			(start -0.67945 -0.3048)
			(end -0.67945 0.3048)
			(stroke
				(width 0.1)
				(type default)
			)
			(layer "B.Fab")
		)
		(pad "1" smd circle
			(at 0.40005 0)
			(size 0 0)
			(layers "B.Cu" "B.Mask" "B.Paste")
			(net "P3V3_AUX")
		)
		(pad "2" smd circle
			(at -0.40005 0)
			(size 0 0)
			(layers "B.Cu" "B.Mask" "B.Paste")
			(net "CPU1_CORETYPE0")
		)
	)
	(footprint ""
		(layer "B.Cu")
		(at 238.708692 -422.849548 90)
		(property "Reference" "C74"
			(at 0 0 90)
			(layer "B.SilkS")
			(hide yes)
			(effects
				(font
					(size 1.27 1.27)
				)
				(justify mirror)
			)
		)
		(property "Value" ""
			(at 0 0 90)
			(layer "B.Fab")
			(effects
				(font
					(size 1.27 1.27)
				)
				(justify mirror)
			)
		)
		(duplicate_pad_numbers_are_jumpers no)
		(fp_line
			(start 0.7874 -0.4064)
			(end -0.7874 -0.4064)
			(stroke
				(width 0.1524)
				(type default)
			)
			(layer "B.SilkS")
		)
		(fp_line
			(start -0.7874 -0.4064)
			(end -0.7874 0.4064)
			(stroke
				(width 0.1524)
				(type default)
			)
			(layer "B.SilkS")
		)
		(fp_line
			(start 0.7874 0.4064)
			(end 0.7874 -0.4064)
			(stroke
				(width 0.1524)
				(type default)
			)
			(layer "B.SilkS")
		)
		(fp_line
			(start -0.7874 0.4064)
			(end 0.7874 0.4064)
			(stroke
				(width 0.1524)
				(type default)
			)
			(layer "B.SilkS")
		)
		(fp_line
			(start 0.67945 -0.305054)
			(end 0.12065 -0.305054)
			(stroke
				(width 0.1)
				(type default)
			)
			(layer "B.Fab")
		)
		(fp_line
			(start 0.12065 -0.305054)
			(end 0.12065 -0.2794)
			(stroke
				(width 0.1)
				(type default)
			)
			(layer "B.Fab")
		)
		(fp_line
			(start -0.12065 -0.3048)
			(end -0.67945 -0.3048)
			(stroke
				(width 0.1)
				(type default)
			)
			(layer "B.Fab")
		)
		(fp_line
			(start -0.67945 -0.3048)
			(end -0.67945 0.3048)
			(stroke
				(width 0.1)
				(type default)
			)
			(layer "B.Fab")
		)
		(fp_line
			(start 0.12065 -0.2794)
			(end -0.12065 -0.2794)
			(stroke
				(width 0.1)
				(type default)
			)
			(layer "B.Fab")
		)
		(fp_line
			(start -0.12065 -0.2794)
			(end -0.12065 -0.3048)
			(stroke
				(width 0.1)
				(type default)
			)
			(layer "B.Fab")
		)
		(fp_line
			(start 0.12065 0.2794)
			(end 0.12065 0.3048)
			(stroke
				(width 0.1)
				(type default)
			)
			(layer "B.Fab")
		)
		(fp_line
			(start -0.120396 0.2794)
			(end 0.12065 0.2794)
			(stroke
				(width 0.1)
				(type default)
			)
			(layer "B.Fab")
		)
		(fp_line
			(start 0.67945 0.3048)
			(end 0.67945 -0.305054)
			(stroke
				(width 0.1)
				(type default)
			)
			(layer "B.Fab")
		)
		(fp_line
			(start 0.12065 0.3048)
			(end 0.67945 0.3048)
			(stroke
				(width 0.1)
				(type default)
			)
			(layer "B.Fab")
		)
		(fp_line
			(start -0.120396 0.3048)
			(end -0.120396 0.2794)
			(stroke
				(width 0.1)
				(type default)
			)
			(layer "B.Fab")
		)
		(fp_line
			(start -0.67945 0.3048)
			(end -0.120396 0.3048)
			(stroke
				(width 0.1)
				(type default)
			)
			(layer "B.Fab")
		)
		(pad "1" smd circle
			(at 0.40005 0 270)
			(size 0 0)
			(layers "B.Cu" "B.Mask" "B.Paste")
			(net "RST_SMB_SWITCH_R_N")
		)
		(pad "2" smd circle
			(at -0.40005 0 270)
			(size 0 0)
			(layers "B.Cu" "B.Mask" "B.Paste")
			(net "GND")
		)
	)
	(footprint ""
		(layer "B.Cu")
		(at 59.51855 -388.011162 -90)
		(property "Reference" "C137"
			(at 0 0 90)
			(layer "B.SilkS")
			(hide yes)
			(effects
				(font
					(size 1.27 1.27)
				)
				(justify mirror)
			)
		)
		(property "Value" ""
			(at 0 0 90)
			(layer "B.Fab")
			(effects
				(font
					(size 1.27 1.27)
				)
				(justify mirror)
			)
		)
		(duplicate_pad_numbers_are_jumpers no)
		(fp_line
			(start -0.299974 0.150114)
			(end 0.299974 0.150114)
			(stroke
				(width 0.1)
				(type default)
			)
			(layer "B.Fab")
		)
		(fp_line
			(start 0.299974 0.150114)
			(end 0.299974 -0.150114)
			(stroke
				(width 0.1)
				(type default)
			)
			(layer "B.Fab")
		)
		(fp_line
			(start -0.299974 -0.150114)
			(end -0.299974 0.150114)
			(stroke
				(width 0.1)
				(type default)
			)
			(layer "B.Fab")
		)
		(fp_line
			(start 0.299974 -0.150114)
			(end -0.299974 -0.150114)
			(stroke
				(width 0.1)
				(type default)
			)
			(layer "B.Fab")
		)
		(pad "1" smd rect
			(at 0.2667 0 90)
			(size 0.3048 0.381)
			(layers "B.Cu" "B.Mask" "B.Paste")
			(net "P0V9_CPU1_RT_2D")
		)
		(pad "2" smd rect
			(at -0.2667 0 90)
			(size 0.3048 0.381)
			(layers "B.Cu" "B.Mask" "B.Paste")
			(net "GND")
		)
	)
)
